# T6G (Grand Teton) — schematic netlist excerpt (pin names and nets, part order shuffled) for the footprints in the layout excerpt that follows; sources: Cadence DE-HDL packaged netlist, KiCad conversion of 04192023_DAF0TMB3IC0_F0TG_MB_C_brd_V02_OCP.brd

R172  Q_RES  33 5% CHIP  pkg 0402LF  page 80 : A = FM_I3C_CPU1_MUX1_R_SEL ; B = FM_I3C_CPU1_MUX1_SEL
R6769  Q_RES  1K 1% CHIP  pkg 0201LF  page 184 : A = P1V8_CPU0_RT_1D ; B = SMB_RT_CPU0_P2_R_SCL
C503  Q_CAP  100UF 4V 20% X6S  pkg C0805  page 279 : A = P1V8_CPU0_RT0_1A ; B = GND

(kicad_pcb
	(version 20260206)
	(generator "pcbnew")
	(generator_version "10.0")
	(general
		(thickness 1.6)
		(legacy_teardrops no)
	)
	(paper "A4")
	(title_block
		(title "04192023_DAF0TMB3IC0_F0TG_MB_C_brd_V02_OCP.brd")
		(comment 1 "Grand Teton / footprints 5617-5619 of 8354")
	)
	(layers
		(0 "F.Cu" signal "TOP")
		(4 "In1.Cu" signal "GND")
		(6 "In2.Cu" signal "IN1")
		(8 "In3.Cu" signal "GND1")
		(10 "In4.Cu" signal "IN2")
		(12 "In5.Cu" signal "GND2")
		(14 "In6.Cu" signal "IN3")
		(16 "In7.Cu" signal "GND3")
		(18 "In8.Cu" signal "VCC")
		(20 "In9.Cu" signal "VCC1")
		(22 "In10.Cu" signal "GND4")
		(24 "In11.Cu" signal "IN4")
		(26 "In12.Cu" signal "GND5")
		(28 "In13.Cu" signal "IN5")
		(30 "In14.Cu" signal "GND6")
		(32 "In15.Cu" signal "IN6")
		(34 "In16.Cu" signal "GND7")
		(2 "B.Cu" signal "BOTTOM")
		(9 "F.Adhes" user "F.Adhesive")
		(11 "B.Adhes" user "B.Adhesive")
		(13 "F.Paste" user "Package Geometry/Pastemask Top")
		(15 "B.Paste" user "Package Geometry/Pastemask Bottom")
		(5 "F.SilkS" user "Ref Des/Silkscreen Top")
		(7 "B.SilkS" user "Ref Des/Silkscreen Bottom")
		(1 "F.Mask" user "Board Geometry/Soldermask Top")
		(3 "B.Mask" user "Board Geometry/Soldermask Bottom")
		(17 "Dwgs.User" user "User.Drawings")
		(19 "Cmts.User" user "User.Comments")
		(21 "Eco1.User" user "User.Eco1")
		(23 "Eco2.User" user "User.Eco2")
		(25 "Edge.Cuts" user "Board Geometry/Outline")
		(27 "Margin" user)
		(31 "F.CrtYd" user "Package Geometry/Place Bound Top")
		(29 "B.CrtYd" user "Package Geometry/Place Bound Bottom")
		(35 "F.Fab" user "Ref Des/Assembly Top")
		(33 "B.Fab" user "Ref Des/Assembly Bottom")
	)
	(footprint ""
		(layer "B.Cu")
		(at 171.2849 -109.055408)
		(property "Reference" "R172"
			(at 0 0 0)
			(layer "B.SilkS")
			(hide yes)
			(effects
				(font
					(size 1.27 1.27)
				)
				(justify mirror)
			)
		)
		(property "Value" ""
			(at 0 0 0)
			(layer "B.Fab")
			(effects
				(font
					(size 1.27 1.27)
				)
				(justify mirror)
			)
		)
		(duplicate_pad_numbers_are_jumpers no)
		(fp_line
			(start -0.7874 -0.4064)
			(end -0.7874 0.4064)
			(stroke
				(width 0.1524)
				(type default)
			)
			(layer "B.SilkS")
		)
		(fp_line
			(start -0.7874 0.4064)
			(end 0.7874 0.4064)
			(stroke
				(width 0.1524)
				(type default)
			)
			(layer "B.SilkS")
		)
		(fp_line
			(start 0.7874 -0.4064)
			(end -0.7874 -0.4064)
			(stroke
				(width 0.1524)
				(type default)
			)
			(layer "B.SilkS")
		)
		(fp_line
			(start 0.7874 0.4064)
			(end 0.7874 -0.4064)
			(stroke
				(width 0.1524)
				(type default)
			)
			(layer "B.SilkS")
		)
		(fp_line
			(start -0.67945 -0.3048)
			(end -0.67945 0.3048)
			(stroke
				(width 0.1)
				(type default)
			)
			(layer "B.Fab")
		)
		(fp_line
			(start -0.67945 0.3048)
			(end -0.120396 0.3048)
			(stroke
				(width 0.1)
				(type default)
			)
			(layer "B.Fab")
		)
		(fp_line
			(start -0.12065 -0.3048)
			(end -0.67945 -0.3048)
			(stroke
				(width 0.1)
				(type default)
			)
			(layer "B.Fab")
		)
		(fp_line
			(start -0.12065 -0.2794)
			(end -0.12065 -0.3048)
			(stroke
				(width 0.1)
				(type default)
			)
			(layer "B.Fab")
		)
		(fp_line
			(start -0.120396 0.2794)
			(end 0.12065 0.2794)
			(stroke
				(width 0.1)
				(type default)
			)
			(layer "B.Fab")
		)
		(fp_line
			(start -0.120396 0.3048)
			(end -0.120396 0.2794)
			(stroke
				(width 0.1)
				(type default)
			)
			(layer "B.Fab")
		)
		(fp_line
			(start 0.12065 -0.305054)
			(end 0.12065 -0.2794)
			(stroke
				(width 0.1)
				(type default)
			)
			(layer "B.Fab")
		)
		(fp_line
			(start 0.12065 -0.2794)
			(end -0.12065 -0.2794)
			(stroke
				(width 0.1)
				(type default)
			)
			(layer "B.Fab")
		)
		(fp_line
			(start 0.12065 0.2794)
			(end 0.12065 0.3048)
			(stroke
				(width 0.1)
				(type default)
			)
			(layer "B.Fab")
		)
		(fp_line
			(start 0.12065 0.3048)
			(end 0.67945 0.3048)
			(stroke
				(width 0.1)
				(type default)
			)
			(layer "B.Fab")
		)
		(fp_line
			(start 0.67945 -0.305054)
			(end 0.12065 -0.305054)
			(stroke
				(width 0.1)
				(type default)
			)
			(layer "B.Fab")
		)
		(fp_line
			(start 0.67945 0.3048)
			(end 0.67945 -0.305054)
			(stroke
				(width 0.1)
				(type default)
			)
			(layer "B.Fab")
		)
		(pad "1" smd circle
			(at 0.40005 0 180)
			(size 0 0)
			(layers "B.Cu" "B.Mask" "B.Paste")
			(net "FM_I3C_CPU1_MUX1_R_SEL")
		)
		(pad "2" smd circle
			(at -0.40005 0 180)
			(size 0 0)
			(layers "B.Cu" "B.Mask" "B.Paste")
			(net "FM_I3C_CPU1_MUX1_SEL")
		)
	)
	(footprint ""
		(layer "B.Cu")
		(at 232.537 -333.883 -90)
		(property "Reference" "R6769"
			(at 0 0 90)
			(layer "B.SilkS")
			(hide yes)
			(effects
				(font
					(size 1.27 1.27)
				)
				(justify mirror)
			)
		)
		(property "Value" ""
			(at 0 0 90)
			(layer "B.Fab")
			(effects
				(font
					(size 1.27 1.27)
				)
				(justify mirror)
			)
		)
		(duplicate_pad_numbers_are_jumpers no)
		(fp_line
			(start -0.32512 0.175006)
			(end 0.32512 0.175006)
			(stroke
				(width 0.1)
				(type default)
			)
			(layer "B.Fab")
		)
		(fp_line
			(start 0.32512 0.175006)
			(end 0.32512 -0.175006)
			(stroke
				(width 0.1)
				(type default)
			)
			(layer "B.Fab")
		)
		(fp_line
			(start -0.32512 -0.175006)
			(end -0.32512 0.175006)
			(stroke
				(width 0.1)
				(type default)
			)
			(layer "B.Fab")
		)
		(fp_line
			(start 0.32512 -0.175006)
			(end -0.32512 -0.175006)
			(stroke
				(width 0.1)
				(type default)
			)
			(layer "B.Fab")
		)
		(pad "1" smd rect
			(at 0.2667 0 90)
			(size 0.3048 0.381)
			(layers "B.Cu" "B.Mask" "B.Paste")
			(net "P1V8_CPU0_RT_1D")
		)
		(pad "2" smd rect
			(at -0.2667 0 270)
			(size 0.3048 0.381)
			(layers "B.Cu" "B.Mask" "B.Paste")
			(net "SMB_RT_CPU0_P2_R_SCL")
		)
	)
	(footprint ""
		(layer "B.Cu")
		(at 324.916038 -395.466062 -90)
		(property "Reference" "C503"
			(at 0 0 90)
			(layer "B.SilkS")
			(hide yes)
			(effects
				(font
					(size 1.27 1.27)
				)
				(justify mirror)
			)
		)
		(property "Value" ""
			(at 0 0 90)
			(layer "B.Fab")
			(effects
				(font
					(size 1.27 1.27)
				)
				(justify mirror)
			)
		)
		(duplicate_pad_numbers_are_jumpers no)
		(fp_line
			(start -1.524 0.762)
			(end 1.524 0.762)
			(stroke
				(width 0.1524)
				(type default)
			)
			(layer "B.SilkS")
		)
		(fp_line
			(start 1.524 0.762)
			(end 1.524 -0.762)
			(stroke
				(width 0.1524)
				(type default)
			)
			(layer "B.SilkS")
		)
		(fp_line
			(start -1.524 -0.762)
			(end -1.524 0.762)
			(stroke
				(width 0.1524)
				(type default)
			)
			(layer "B.SilkS")
		)
		(fp_line
			(start 1.524 -0.762)
			(end -1.524 -0.762)
			(stroke
				(width 0.1524)
				(type default)
			)
			(layer "B.SilkS")
		)
		(fp_line
			(start -1.1049 0.724916)
			(end -1.1049 -0.724916)
			(stroke
				(width 0.1)
				(type default)
			)
			(layer "B.Fab")
		)
		(fp_line
			(start 1.1049 0.724916)
			(end -1.1049 0.724916)
			(stroke
				(width 0.1)
				(type default)
			)
			(layer "B.Fab")
		)
		(fp_line
			(start -1.1049 -0.724916)
			(end 1.1049 -0.724916)
			(stroke
				(width 0.1)
				(type default)
			)
			(layer "B.Fab")
		)
		(fp_line
			(start 1.1049 -0.724916)
			(end 1.1049 0.724916)
			(stroke
				(width 0.1)
				(type default)
			)
			(layer "B.Fab")
		)
		(pad "1" smd rect
			(at 0.889 0 270)
			(size 1.016 1.27)
			(layers "B.Cu" "B.Mask" "B.Paste")
			(net "P1V8_CPU0_RT0_1A")
		)
		(pad "2" smd rect
			(at -0.889 0 270)
			(size 1.016 1.27)
			(layers "B.Cu" "B.Mask" "B.Paste")
			(net "GND")
		)
	)
)
